(kicad_pcb
	(version 20221018)
	(generator pcbnew)
	(general
    (thickness 1.518)
  )
	(paper "A4")
	(title_block
    (title "Kria K26 Devboard")
    (date "2024-03-26")
    (rev "1.2.5")
    (comment 1 "www.antmicro.com")
    (comment 2 "Antmicro Ltd.")
		(comment 9 "footprints 118-120 of 660")
	)
	(layers
    (0 "F.Cu" mixed)
    (1 "In1.Cu" power)
    (2 "In2.Cu" mixed)
    (3 "In3.Cu" power)
    (4 "In4.Cu" mixed)
    (5 "In5.Cu" power)
    (6 "In6.Cu" mixed)
    (31 "B.Cu" power)
    (32 "B.Adhes" user "B.Adhesive")
    (33 "F.Adhes" user "F.Adhesive")
    (34 "B.Paste" user)
    (35 "F.Paste" user)
    (36 "B.SilkS" user "B.Silkscreen")
    (37 "F.SilkS" user "F.Silkscreen")
    (38 "B.Mask" user)
    (39 "F.Mask" user)
    (40 "Dwgs.User" user "User.Drawings")
    (41 "Cmts.User" user "User.Comments")
    (42 "Eco1.User" user "User.Eco1")
    (43 "Eco2.User" user "User.Eco2")
    (44 "Edge.Cuts" user)
    (45 "Margin" user)
    (46 "B.CrtYd" user "B.Courtyard")
    (47 "F.CrtYd" user "F.Courtyard")
    (48 "B.Fab" user)
    (49 "F.Fab" user)
  )
	(footprint "kria-k26-devboard-footprints:UQFN-16-1.8x2.6mm_P0.4mm_Texas_RSV0016A" (layer "F.Cu")
    (at 139.225 116.925 90)
    (descr "https://www.ti.com/lit/ds/symlink/sn74avch4t245-ep.pdf?ts=1679484181203&ref_url=https%253A%252F%252Fwww.ti.com%252Fproduct%252FSN74AVCH4T245-EP%253Futm_source%253Dgoogle%2526utm_medium%253Dcpc%2526utm_campaign%253Dasc-int-null-prodfolderdynamic-cpc-pf-google-wwe_int%2526utm_content%253Dprodfolddynamic%2526ds_k%253DDYNAMIC%2BSEARCH%2BADS%2526DCM%253Dyes%2526gclid%253DCjwKCAjwzuqgBhAcEiwAdj5dRvR_WgyvqqhLxMx8zfbFv2a6tg33JIMv01Bn4M1kA4JzW1nDDW7OzhoCRbkQAvD_BwE%2526gclsrc%253Daw.ds")
    (property "Author" "Antmicro")
    (property "License" "Apache-2.0")
    (property "MPN" "74AVC4T245RSVRG4")
    (property "Manufacturer" "Texas Instruments")
    (property "Sheetfile" "debug.kicad_sch")
    (property "Sheetname" "Debug and JTAG")
    (property "ki_description" "Logic translator/level shifter")
    (property "ki_keywords" "SMT, LOGIC, IC, LEVEL-SHIFTER")
    (attr smd)
    (fp_text reference "U42" (at -2.035 -1.855 180) (layer "F.SilkS")
        (effects (font (size 0.7 0.7) (thickness 0.15)) (justify left bottom))
    )
    (fp_text value "74AVC4T245_UQFN" (at -1.25 2.5 90) (layer "F.Fab") hide
        (effects (font (size 0.7 0.7) (thickness 0.15)) (justify left bottom))
    )
    (fp_text user "." (at -1.315 -0.775 90) (layer "F.SilkS")
        (effects (font (size 0.7 0.7) (thickness 0.15)) (justify left bottom))
    )
    (fp_text user "Author: Antmicro" (at -1.25 5 90) (layer "F.Fab") hide
        (effects (font (size 0.7 0.7) (thickness 0.15)) (justify left bottom))
    )
    (fp_text user "${REFERENCE}" (at -1.25 3.75 90) (layer "F.Fab") hide
        (effects (font (size 0.7 0.7) (thickness 0.15)) (justify left bottom))
    )
    (fp_text user "License: Apache-2.0" (at -1.25 6.25 90) (layer "F.Fab") hide
        (effects (font (size 0.7 0.7) (thickness 0.15)) (justify left bottom))
    )
    (fp_line (start -0.9 1.2995) (end -0.9 0.8)
      (stroke (width 0.15) (type solid)) (layer "F.SilkS"))
    (fp_line (start -0.8 -1.3) (end -0.9 -1.3)
      (stroke (width 0.15) (type solid)) (layer "F.SilkS"))
    (fp_line (start -0.8 1.2995) (end -0.9 1.2995)
      (stroke (width 0.15) (type solid)) (layer "F.SilkS"))
    (fp_line (start 0.8 -1.3) (end 0.9 -1.3)
      (stroke (width 0.15) (type solid)) (layer "F.SilkS"))
    (fp_line (start 0.8 1.3) (end 0.899 1.3)
      (stroke (width 0.15) (type solid)) (layer "F.SilkS"))
    (fp_line (start 0.9 -1.3) (end 0.9 -0.8005)
      (stroke (width 0.15) (type solid)) (layer "F.SilkS"))
    (fp_line (start 0.9 0.8) (end 0.899 1.3)
      (stroke (width 0.15) (type solid)) (layer "F.SilkS"))
    (fp_rect (start -1.25 -1.65) (end 1.25 1.65)
      (stroke (width 0.05) (type solid)) (fill none) (layer "F.CrtYd"))
    (fp_line (start -0.902 1.3) (end -0.902 -1.301)
      (stroke (width 0.15) (type solid)) (layer "F.Fab"))
    (fp_line (start 0.9 -1.301) (end -0.902 -1.301)
      (stroke (width 0.15) (type solid)) (layer "F.Fab"))
    (fp_line (start 0.9 1.3) (end -0.902 1.3)
      (stroke (width 0.15) (type solid)) (layer "F.Fab"))
    (fp_line (start 0.9 1.3) (end 0.9 -1.301)
      (stroke (width 0.15) (type solid)) (layer "F.Fab"))
    (pad "1" smd roundrect (at -0.75 -0.6 90) (size 0.7 0.2) (layers "F.Cu" "F.Paste" "F.Mask") (roundrect_rratio 0.2272727273)
      (net 160 "/Debug and JTAG/~{LS_OE}") (pinfunction "1~{OE}") (pintype "input"))
    (pad "2" smd roundrect (at -0.802 -0.202 90) (size 0.6 0.2) (layers "F.Cu" "F.Paste" "F.Mask") (roundrect_rratio 0.2272727273)
      (net 17 "PS_1V8") (pinfunction "VCCB") (pintype "power_in"))
    (pad "3" smd roundrect (at -0.802 0.2 90) (size 0.6 0.2) (layers "F.Cu" "F.Paste" "F.Mask") (roundrect_rratio 0.2272727273)
      (net 138 "/Debug and JTAG/USB_3V3") (pinfunction "VCCA") (pintype "power_in"))
    (pad "4" smd roundrect (at -0.802 0.598 90) (size 0.6 0.2) (layers "F.Cu" "F.Paste" "F.Mask") (roundrect_rratio 0.2272727273)
      (net 138 "/Debug and JTAG/USB_3V3") (pinfunction "1DIR") (pintype "input"))
    (pad "5" smd roundrect (at -0.6 1.199 180) (size 0.6 0.2) (layers "F.Cu" "F.Paste" "F.Mask") (roundrect_rratio 0.2272727273)
      (net 138 "/Debug and JTAG/USB_3V3") (pinfunction "2DIR") (pintype "input"))
    (pad "6" smd roundrect (at -0.202 1.199 180) (size 0.6 0.2) (layers "F.Cu" "F.Paste" "F.Mask") (roundrect_rratio 0.2272727273)
      (net 170 "/Debug and JTAG/FTDI_TMS") (pinfunction "1A1") (pintype "bidirectional"))
    (pad "7" smd roundrect (at 0.2 1.199 180) (size 0.6 0.2) (layers "F.Cu" "F.Paste" "F.Mask") (roundrect_rratio 0.2272727273)
      (net 173 "/Debug and JTAG/FTDI_TCK") (pinfunction "1A2") (pintype "bidirectional"))
    (pad "8" smd roundrect (at 0.598 1.199 180) (size 0.6 0.2) (layers "F.Cu" "F.Paste" "F.Mask") (roundrect_rratio 0.2272727273)
      (net 172 "/Debug and JTAG/FTDI_TDI") (pinfunction "2A1") (pintype "bidirectional"))
    (pad "9" smd roundrect (at 0.8 0.598 90) (size 0.6 0.2) (layers "F.Cu" "F.Paste" "F.Mask") (roundrect_rratio 0.2272727273)
      (net 1 "GND") (pinfunction "2A2") (pintype "bidirectional"))
    (pad "10" smd roundrect (at 0.8 0.2 90) (size 0.6 0.2) (layers "F.Cu" "F.Paste" "F.Mask") (roundrect_rratio 0.2272727273)
      (net 1 "GND") (pinfunction "GND") (pintype "power_in"))
    (pad "11" smd roundrect (at 0.8 -0.202 90) (size 0.6 0.2) (layers "F.Cu" "F.Paste" "F.Mask") (roundrect_rratio 0.2272727273)
      (net 1 "GND") (pinfunction "GND") (pintype "passive"))
    (pad "12" smd roundrect (at 0.8 -0.6 90) (size 0.6 0.2) (layers "F.Cu" "F.Paste" "F.Mask") (roundrect_rratio 0.2272727273)
      (net 776 "unconnected-(U42-2B2-Pad12)") (pinfunction "2B2") (pintype "bidirectional+no_connect"))
    (pad "13" smd roundrect (at 0.598 -1.2 180) (size 0.6 0.2) (layers "F.Cu" "F.Paste" "F.Mask") (roundrect_rratio 0.2272727273)
      (net 141 "/Debug and JTAG/JTAG_TDI_C2M") (pinfunction "2B1") (pintype "bidirectional"))
    (pad "14" smd roundrect (at 0.2 -1.2 180) (size 0.6 0.2) (layers "F.Cu" "F.Paste" "F.Mask") (roundrect_rratio 0.2272727273)
      (net 143 "/Debug and JTAG/JTAG_TCK_C2M") (pinfunction "1B2") (pintype "bidirectional"))
    (pad "15" smd roundrect (at -0.202 -1.2 180) (size 0.6 0.2) (layers "F.Cu" "F.Paste" "F.Mask") (roundrect_rratio 0.2272727273)
      (net 145 "/Debug and JTAG/JTAG_TMS_C2M") (pinfunction "1B1") (pintype "bidirectional"))
    (pad "16" smd roundrect (at -0.6 -1.2 180) (size 0.6 0.2) (layers "F.Cu" "F.Paste" "F.Mask") (roundrect_rratio 0.2272727273)
      (net 160 "/Debug and JTAG/~{LS_OE}") (pinfunction "2~{OE}") (pintype "input"))
  )
	(footprint "kria-k26-devboard-footprints:R_0402_1005Metric" (layer "F.Cu")
    (at 142.8 116.2)
    (descr "Resistor SMD 0402")
    (tags "resistor SMD 0402")
    (property "Author" "Antmicro")
    (property "License" "Apache-2.0")
    (property "MPN" "CR0402-FX-1002GLF")
    (property "Manufacturer" "Bourns")
    (property "Sheetfile" "debug.kicad_sch")
    (property "Sheetname" "Debug and JTAG")
    (property "Tolerance" "1%")
    (property "Val" "10k")
    (property "ki_description" "10k resistor in 0402 package with 1% tolerance")
    (attr smd)
    (fp_text reference "R103" (at -1.68 1.33) (layer "F.SilkS")
        (effects (font (size 0.7 0.7) (thickness 0.15)) (justify left bottom))
    )
    (fp_text value "R_10k_0402" (at 0 1.4) (layer "F.Fab") hide
        (effects (font (size 0.7 0.7) (thickness 0.15)) (justify left bottom))
    )
    (fp_text user "License: Apache-2.0" (at -0.95 5.169) (layer "F.Fab") hide
        (effects (font (size 0.7 0.7) (thickness 0.15)) (justify left bottom))
    )
    (fp_text user "Author: Antmicro" (at -0.95 4.169) (layer "F.Fab") hide
        (effects (font (size 0.7 0.7) (thickness 0.15)) (justify left bottom))
    )
    (fp_text user "${REFERENCE}" (at -0.95 3.168) (layer "F.Fab") hide
        (effects (font (size 0.7 0.7) (thickness 0.15)) (justify left bottom))
    )
    (fp_rect (start -0.93 -0.47) (end 0.93 0.47)
      (stroke (width 0.05) (type solid)) (fill none) (layer "F.CrtYd"))
    (fp_rect (start -0.5 -0.25) (end 0.5 0.25)
      (stroke (width 0.15) (type solid)) (fill none) (layer "F.Fab"))
    (pad "1" smd roundrect (at -0.485 0) (size 0.59 0.64) (layers "F.Cu" "F.Paste" "F.Mask") (roundrect_rratio 0.25)
      (net 138 "/Debug and JTAG/USB_3V3") (pintype "passive"))
    (pad "2" smd roundrect (at 0.485 0) (size 0.59 0.64) (layers "F.Cu" "F.Paste" "F.Mask") (roundrect_rratio 0.25)
      (net 681 "Net-(U40-~{RESET})") (pintype "passive"))
  )
	(footprint "kria-k26-devboard-footprints:R_0402_1005Metric" (layer "F.Cu")
    (at 142.825 120.26)
    (descr "Resistor SMD 0402")
    (tags "resistor SMD 0402")
    (property "Author" "Antmicro")
    (property "License" "Apache-2.0")
    (property "MPN" "CR0402-FX-1002GLF")
    (property "Manufacturer" "Bourns")
    (property "Sheetfile" "debug.kicad_sch")
    (property "Sheetname" "Debug and JTAG")
    (property "Tolerance" "1%")
    (property "Val" "10k")
    (property "ki_description" "10k resistor in 0402 package with 1% tolerance")
    (attr smd)
    (fp_text reference "R109" (at -1.785 -0.49) (layer "F.SilkS")
        (effects (font (size 0.7 0.7) (thickness 0.15)) (justify left bottom))
    )
    (fp_text value "R_10k_0402" (at 0 1.4) (layer "F.Fab") hide
        (effects (font (size 0.7 0.7) (thickness 0.15)) (justify left bottom))
    )
    (fp_text user "Author: Antmicro" (at -0.95 4.169) (layer "F.Fab") hide
        (effects (font (size 0.7 0.7) (thickness 0.15)) (justify left bottom))
    )
    (fp_text user "${REFERENCE}" (at -0.95 3.168) (layer "F.Fab") hide
        (effects (font (size 0.7 0.7) (thickness 0.15)) (justify left bottom))
    )
    (fp_text user "License: Apache-2.0" (at -0.95 5.169) (layer "F.Fab") hide
        (effects (font (size 0.7 0.7) (thickness 0.15)) (justify left bottom))
    )
    (fp_rect (start -0.93 -0.47) (end 0.93 0.47)
      (stroke (width 0.05) (type solid)) (fill none) (layer "F.CrtYd"))
    (fp_rect (start -0.5 -0.25) (end 0.5 0.25)
      (stroke (width 0.15) (type solid)) (fill none) (layer "F.Fab"))
    (pad "1" smd roundrect (at -0.485 0) (size 0.59 0.64) (layers "F.Cu" "F.Paste" "F.Mask") (roundrect_rratio 0.25)
      (net 138 "/Debug and JTAG/USB_3V3") (pintype "passive"))
    (pad "2" smd roundrect (at 0.485 0) (size 0.59 0.64) (layers "F.Cu" "F.Paste" "F.Mask") (roundrect_rratio 0.25)
      (net 159 "/Debug and JTAG/~{FTDI_LS_OE}") (pintype "passive"))
  )
)
